(kicad_pcb
	(version 20240108)
	(generator "pcbnew")
	(generator_version "8.0")
	(general
		(thickness 1.62)
		(legacy_teardrops no)
	)
	(paper "A4")
	(title_block
		(title "Jetson Orin Baseboard")
		(date "2025-03-12")
		(rev "1.3.4")
		(company "Antmicro Ltd")
		(comment 1 "www.antmicro.com")
		(comment 9 "footprint 244 of 677 (J11), pads 1-82 of 82")
	)
	(layers
		(0 "F.Cu" signal)
		(1 "In1.Cu" signal)
		(2 "In2.Cu" signal)
		(3 "In3.Cu" signal)
		(4 "In4.Cu" jumper)
		(5 "In5.Cu" signal)
		(6 "In6.Cu" signal)
		(31 "B.Cu" signal)
		(32 "B.Adhes" user "B.Adhesive")
		(33 "F.Adhes" user "F.Adhesive")
		(34 "B.Paste" user)
		(35 "F.Paste" user)
		(36 "B.SilkS" user "B.Silkscreen")
		(37 "F.SilkS" user "F.Silkscreen")
		(38 "B.Mask" user)
		(39 "F.Mask" user)
		(40 "Dwgs.User" user "User.Drawings")
		(41 "Cmts.User" user "User.Comments")
		(42 "Eco1.User" user "User.Eco1")
		(43 "Eco2.User" user "User.Eco2")
		(44 "Edge.Cuts" user)
		(45 "Margin" user)
		(46 "B.CrtYd" user "B.Courtyard")
		(47 "F.CrtYd" user "F.Courtyard")
		(48 "B.Fab" user)
		(49 "F.Fab" user)
	)
	(footprint "antmicro-footprints:Conn_Socket_Samtec_ERF8_2x40_ERF8-040-05.0-L-DV-K-TR"
		(layer "F.Cu")
		(at 143.75 98.75 -90)
		(property "Reference" "J11"
			(at -4.94 -3.95 90)
			(layer "F.SilkS")
			(effects
				(font
					(size 0.7 0.7)
					(thickness 0.15)
				)
				(justify left bottom)
			)
		)
		(property "Value" "Socket_Samtec_ERF8_2x40_ERF8-040-05.0-L-DV-K-TR"
			(at 0 4 90)
			(layer "F.Fab")
			(effects
				(font
					(size 0.7 0.7)
					(thickness 0.15)
				)
				(justify right bottom)
			)
		)
		(property "Footprint" "antmicro-footprints:Conn_Socket_Samtec_ERF8_2x40_ERF8-040-05.0-L-DV-K-TR"
			(at 0 0 -90)
			(layer "F.Fab")
			(hide yes)
			(effects
				(font
					(size 1.27 1.27)
					(thickness 0.15)
				)
			)
		)
		(property "Datasheet" "https://suddendocs.samtec.com/catalog_english/erf8.pdf"
			(at 0 0 -90)
			(layer "F.Fab")
			(hide yes)
			(effects
				(font
					(size 1.27 1.27)
					(thickness 0.15)
				)
			)
		)
		(property "Author" "Antmicro"
			(at 45 242.5 0)
			(layer "F.Fab")
			(hide yes)
			(effects
				(font
					(size 1 1)
					(thickness 0.15)
				)
			)
		)
		(property "License" "Apache-2.0"
			(at 45 242.5 0)
			(layer "F.Fab")
			(hide yes)
			(effects
				(font
					(size 1 1)
					(thickness 0.15)
				)
			)
		)
		(property "MPN" "ERF8-040-05.0-L-DV-K-TR"
			(at 45 242.5 0)
			(layer "F.Fab")
			(hide yes)
			(effects
				(font
					(size 1 1)
					(thickness 0.15)
				)
			)
		)
		(property "Manufacturer" "Samtec"
			(at 45 242.5 0)
			(layer "F.Fab")
			(hide yes)
			(effects
				(font
					(size 1 1)
					(thickness 0.15)
				)
			)
		)
		(property "Pitch" "0.8 mm"
			(at 45 242.5 0)
			(layer "F.Fab")
			(hide yes)
			(effects
				(font
					(size 1 1)
					(thickness 0.15)
				)
			)
		)
		(sheetname "Peripherals")
		(sheetfile "peripherals.kicad_sch")
		(attr smd)
		(pad "" np_thru_hole circle
			(at -17.4 -1.499 90)
			(size 1.45 1.45)
			(drill 1.45)
			(layers "*.Mask")
		)
		(pad "" np_thru_hole circle
			(at 17.399 -1.499 90)
			(size 1.45 1.45)
			(drill 1.45)
			(layers "*.Mask")
		)
		(pad "1" smd rect
			(at -15.599 2.249 90)
			(size 0.5 1.1)
			(layers "F.Cu" "F.Paste" "F.Mask")
			(net 1 "GND")
			(pintype "passive")
		)
		(pad "2" smd rect
			(at -15.599 -2.249 90)
			(size 0.5 1.1)
			(layers "F.Cu" "F.Paste" "F.Mask")
			(net 1 "GND")
			(pintype "passive")
		)
		(pad "3" smd rect
			(at -14.801 2.249 90)
			(size 0.5 1.1)
			(layers "F.Cu" "F.Paste" "F.Mask")
			(net 415 "/Peripherals/PCIE2_TX1_CONN_N")
			(pintype "passive")
		)
		(pad "4" smd rect
			(at -14.801 -2.249 90)
			(size 0.5 1.1)
			(layers "F.Cu" "F.Paste" "F.Mask")
			(net 1 "GND")
			(pintype "passive")
		)
		(pad "5" smd rect
			(at -14 2.249 90)
			(size 0.5 1.1)
			(layers "F.Cu" "F.Paste" "F.Mask")
			(net 413 "/Peripherals/PCIE2_TX1_CONN_P")
			(pintype "passive")
		)
		(pad "6" smd rect
			(at -14 -2.249 90)
			(size 0.5 1.1)
			(layers "F.Cu" "F.Paste" "F.Mask")
			(net 172 "PCIE2_RX1_N")
			(pintype "passive")
		)
		(pad "7" smd rect
			(at -13.199 2.249 90)
			(size 0.5 1.1)
			(layers "F.Cu" "F.Paste" "F.Mask")
			(net 1 "GND")
			(pintype "passive")
		)
		(pad "8" smd rect
			(at -13.199 -2.249 90)
			(size 0.5 1.1)
			(layers "F.Cu" "F.Paste" "F.Mask")
			(net 175 "PCIE2_RX1_P")
			(pintype "passive")
		)
		(pad "9" smd rect
			(at -12.401 2.249 90)
			(size 0.5 1.1)
			(layers "F.Cu" "F.Paste" "F.Mask")
			(net 411 "/Peripherals/PCIE2_TX0_CONN_N")
			(pintype "passive")
		)
		(pad "10" smd rect
			(at -12.401 -2.249 90)
			(size 0.5 1.1)
			(layers "F.Cu" "F.Paste" "F.Mask")
			(net 1 "GND")
			(pintype "passive")
		)
		(pad "11" smd rect
			(at -11.599 2.249 90)
			(size 0.5 1.1)
			(layers "F.Cu" "F.Paste" "F.Mask")
			(net 412 "/Peripherals/PCIE2_TX0_CONN_P")
			(pintype "passive")
		)
		(pad "12" smd rect
			(at -11.599 -2.249 90)
			(size 0.5 1.1)
			(layers "F.Cu" "F.Paste" "F.Mask")
			(net 113 "PCIE2_RX0_N")
			(pintype "passive")
		)
		(pad "13" smd rect
			(at -10.801 2.249 90)
			(size 0.5 1.1)
			(layers "F.Cu" "F.Paste" "F.Mask")
			(net 1 "GND")
			(pintype "passive")
		)
		(pad "14" smd rect
			(at -10.801 -2.249 90)
			(size 0.5 1.1)
			(layers "F.Cu" "F.Paste" "F.Mask")
			(net 131 "PCIE2_RX0_P")
			(pintype "passive")
		)
		(pad "15" smd rect
			(at -10 2.249 90)
			(size 0.5 1.1)
			(layers "F.Cu" "F.Paste" "F.Mask")
			(net 163 "PCIE2_CLK_N")
			(pintype "passive")
		)
		(pad "16" smd rect
			(at -10 -2.249 90)
			(size 0.5 1.1)
			(layers "F.Cu" "F.Paste" "F.Mask")
			(net 1 "GND")
			(pintype "passive")
		)
		(pad "17" smd rect
			(at -9.199 2.249 90)
			(size 0.5 1.1)
			(layers "F.Cu" "F.Paste" "F.Mask")
			(net 166 "PCIE2_CLK_P")
			(pintype "passive")
		)
		(pad "18" smd rect
			(at -9.199 -2.249 90)
			(size 0.5 1.1)
			(layers "F.Cu" "F.Paste" "F.Mask")
			(net 471 "PCIE3_CLK_N")
			(pintype "passive")
		)
		(pad "19" smd rect
			(at -8.401 2.249 90)
			(size 0.5 1.1)
			(layers "F.Cu" "F.Paste" "F.Mask")
			(net 1 "GND")
			(pintype "passive")
		)
		(pad "20" smd rect
			(at -8.401 -2.249 90)
			(size 0.5 1.1)
			(layers "F.Cu" "F.Paste" "F.Mask")
			(net 472 "PCIE3_CLK_P")
			(pintype "passive")
		)
		(pad "21" smd rect
			(at -7.6 2.249 90)
			(size 0.5 1.1)
			(layers "F.Cu" "F.Paste" "F.Mask")
			(net 416 "/Peripherals/USBSS2_TX_CONN_N")
			(pintype "passive")
		)
		(pad "22" smd rect
			(at -7.6 -2.249 90)
			(size 0.5 1.1)
			(layers "F.Cu" "F.Paste" "F.Mask")
			(net 1 "GND")
			(pintype "passive")
		)
		(pad "23" smd rect
			(at -6.8 2.249 90)
			(size 0.5 1.1)
			(layers "F.Cu" "F.Paste" "F.Mask")
			(net 414 "/Peripherals/USBSS2_TX_CONN_P")
			(pintype "passive")
		)
		(pad "24" smd rect
			(at -6.8 -2.249 90)
			(size 0.5 1.1)
			(layers "F.Cu" "F.Paste" "F.Mask")
			(net 107 "USBSS1_RX_N")
			(pintype "passive")
		)
		(pad "25" smd rect
			(at -5.999 2.249 90)
			(size 0.5 1.1)
			(layers "F.Cu" "F.Paste" "F.Mask")
			(net 1 "GND")
			(pintype "passive")
		)
		(pad "26" smd rect
			(at -5.999 -2.249 90)
			(size 0.5 1.1)
			(layers "F.Cu" "F.Paste" "F.Mask")
			(net 114 "USBSS1_RX_P")
			(pintype "passive")
		)
		(pad "27" smd rect
			(at -5.201 2.249 90)
			(size 0.5 1.1)
			(layers "F.Cu" "F.Paste" "F.Mask")
			(net 345 "/Peripherals/PCIE2_RST_CONN*")
			(pintype "passive")
		)
		(pad "28" smd rect
			(at -5.201 -2.249 90)
			(size 0.5 1.1)
			(layers "F.Cu" "F.Paste" "F.Mask")
			(net 1 "GND")
			(pintype "passive")
		)
		(pad "29" smd rect
			(at -4.401 2.249 90)
			(size 0.5 1.1)
			(layers "F.Cu" "F.Paste" "F.Mask")
			(net 346 "/Peripherals/PCIE2_CLKREQ_CONN*")
			(pintype "passive")
		)
		(pad "30" smd rect
			(at -4.401 -2.249 90)
			(size 0.5 1.1)
			(layers "F.Cu" "F.Paste" "F.Mask")
			(net 347 "/Peripherals/PCIE3_RST_CONN*")
			(pintype "passive")
		)
		(pad "31" smd rect
			(at -3.601 2.249 90)
			(size 0.5 1.1)
			(layers "F.Cu" "F.Paste" "F.Mask")
			(net 348 "/Peripherals/GPIO01_CONN")
			(pintype "passive")
		)
		(pad "32" smd rect
			(at -3.601 -2.249 90)
			(size 0.5 1.1)
			(layers "F.Cu" "F.Paste" "F.Mask")
			(net 513 "/Peripherals/PCIE3_CLKREQ_CONN*")
			(pintype "passive")
		)
		(pad "33" smd rect
			(at -2.799 2.249 90)
			(size 0.5 1.1)
			(layers "F.Cu" "F.Paste" "F.Mask")
			(net 515 "/Peripherals/GPIO07_CONN")
			(pintype "passive")
		)
		(pad "34" smd rect
			(at -2.799 -2.249 90)
			(size 0.5 1.1)
			(layers "F.Cu" "F.Paste" "F.Mask")
			(net 578 "/Peripherals/PCIE_WAKE_SEL_EXT_CONN")
			(pintype "passive")
		)
		(pad "35" smd rect
			(at -2 2.249 90)
			(size 0.5 1.1)
			(layers "F.Cu" "F.Paste" "F.Mask")
			(net 579 "/Peripherals/GPIO09_CONN")
			(pintype "passive")
		)
		(pad "36" smd rect
			(at -2 -2.249 90)
			(size 0.5 1.1)
			(layers "F.Cu" "F.Paste" "F.Mask")
			(net 580 "/Peripherals/GPIO13_CONN")
			(pintype "passive")
		)
		(pad "37" smd rect
			(at -1.2 2.249 90)
			(size 0.5 1.1)
			(layers "F.Cu" "F.Paste" "F.Mask")
			(net 1 "GND")
			(pintype "passive")
		)
		(pad "38" smd rect
			(at -1.2 -2.249 90)
			(size 0.5 1.1)
			(layers "F.Cu" "F.Paste" "F.Mask")
			(net 1 "GND")
			(pintype "passive")
		)
		(pad "39" smd rect
			(at -0.401 2.249 90)
			(size 0.5 1.1)
			(layers "F.Cu" "F.Paste" "F.Mask")
			(net 584 "/Peripherals/UART1_RXD_CONN")
			(pintype "passive")
		)
		(pad "40" smd rect
			(at -0.401 -2.249 90)
			(size 0.5 1.1)
			(layers "F.Cu" "F.Paste" "F.Mask")
			(net 581 "/Peripherals/GPIO12_CONN")
			(pintype "passive")
		)
		(pad "41" smd rect
			(at 0.401 2.249 90)
			(size 0.5 1.1)
			(layers "F.Cu" "F.Paste" "F.Mask")
			(net 618 "/Peripherals/USB_CONN_N")
			(pintype "passive")
		)
		(pad "42" smd rect
			(at 0.401 -2.249 90)
			(size 0.5 1.1)
			(layers "F.Cu" "F.Paste" "F.Mask")
			(net 583 "/Peripherals/GPIO11_CONN")
			(pintype "passive")
		)
		(pad "43" smd rect
			(at 1.199 2.249 90)
			(size 0.5 1.1)
			(layers "F.Cu" "F.Paste" "F.Mask")
			(net 619 "/Peripherals/USB_CONN_P")
			(pintype "passive")
		)
		(pad "44" smd rect
			(at 1.199 -2.249 90)
			(size 0.5 1.1)
			(layers "F.Cu" "F.Paste" "F.Mask")
			(net 582 "/Peripherals/UART1_TXD_CONN")
			(pintype "passive")
		)
		(pad "45" smd rect
			(at 1.999 2.249 90)
			(size 0.5 1.1)
			(layers "F.Cu" "F.Paste" "F.Mask")
			(net 585 "/Peripherals/I2S0_SDIN_CONN")
			(pintype "passive")
		)
		(pad "46" smd rect
			(at 1.999 -2.249 90)
			(size 0.5 1.1)
			(layers "F.Cu" "F.Paste" "F.Mask")
			(net 586 "/Peripherals/I2S0_SCLK_CONN")
			(pintype "passive")
		)
		(pad "47" smd rect
			(at 2.799 2.249 90)
			(size 0.5 1.1)
			(layers "F.Cu" "F.Paste" "F.Mask")
			(net 587 "/Peripherals/I2S0_LRCK_CONN")
			(pintype "passive")
		)
		(pad "48" smd rect
			(at 2.799 -2.249 90)
			(size 0.5 1.1)
			(layers "F.Cu" "F.Paste" "F.Mask")
			(net 588 "/Peripherals/I2S0_SDOUT_CONN")
			(pintype "passive")
		)
		(pad "49" smd rect
			(at 3.6 2.249 90)
			(size 0.5 1.1)
			(layers "F.Cu" "F.Paste" "F.Mask")
			(net 1 "GND")
			(pintype "passive")
		)
		(pad "50" smd rect
			(at 3.6 -2.249 90)
			(size 0.5 1.1)
			(layers "F.Cu" "F.Paste" "F.Mask")
			(net 1 "GND")
			(pintype "passive")
		)
		(pad "51" smd rect
			(at 4.4 2.249 90)
			(size 0.5 1.1)
			(layers "F.Cu" "F.Paste" "F.Mask")
			(net 589 "/Peripherals/SPIO_SCK_CONN")
			(pintype "passive")
		)
		(pad "52" smd rect
			(at 4.4 -2.249 90)
			(size 0.5 1.1)
			(layers "F.Cu" "F.Paste" "F.Mask")
			(net 590 "/Peripherals/SPI1_SCK_CONN")
			(pintype "passive")
		)
		(pad "53" smd rect
			(at 5.2 2.249 90)
			(size 0.5 1.1)
			(layers "F.Cu" "F.Paste" "F.Mask")
			(net 591 "/Peripherals/SPIO_MOSI_CONN")
			(pintype "passive")
		)
		(pad "54" smd rect
			(at 5.2 -2.249 90)
			(size 0.5 1.1)
			(layers "F.Cu" "F.Paste" "F.Mask")
			(net 592 "/Peripherals/SPI1_MOSI_CONN")
			(pintype "passive")
		)
		(pad "55" smd rect
			(at 5.999 2.249 90)
			(size 0.5 1.1)
			(layers "F.Cu" "F.Paste" "F.Mask")
			(net 593 "/Peripherals/SPIO_MISO_CONN")
			(pintype "passive")
		)
		(pad "56" smd rect
			(at 5.999 -2.249 90)
			(size 0.5 1.1)
			(layers "F.Cu" "F.Paste" "F.Mask")
			(net 594 "/Peripherals/SPI1_MISO_CONN")
			(pintype "passive")
		)
		(pad "57" smd rect
			(at 6.799 2.249 90)
			(size 0.5 1.1)
			(layers "F.Cu" "F.Paste" "F.Mask")
			(net 595 "/Peripherals/~{SPI0_CS0_CONN}")
			(pintype "passive")
		)
		(pad "58" smd rect
			(at 6.799 -2.249 90)
			(size 0.5 1.1)
			(layers "F.Cu" "F.Paste" "F.Mask")
			(net 606 "/Peripherals/~{SPI1_CS0_CONN}")
			(pintype "passive")
		)
		(pad "59" smd rect
			(at 7.599 2.249 90)
			(size 0.5 1.1)
			(layers "F.Cu" "F.Paste" "F.Mask")
			(net 607 "/Peripherals/~{SPI0_CS1_CONN}")
			(pintype "passive")
		)
		(pad "60" smd rect
			(at 7.599 -2.249 90)
			(size 0.5 1.1)
			(layers "F.Cu" "F.Paste" "F.Mask")
			(net 608 "/Peripherals/~{SPI1_CS1_CONN}")
			(pintype "passive")
		)
		(pad "61" smd rect
			(at 8.4 2.249 90)
			(size 0.5 1.1)
			(layers "F.Cu" "F.Paste" "F.Mask")
			(net 1 "GND")
			(pintype "passive")
		)
		(pad "62" smd rect
			(at 8.4 -2.249 90)
			(size 0.5 1.1)
			(layers "F.Cu" "F.Paste" "F.Mask")
			(net 1 "GND")
			(pintype "passive")
		)
		(pad "63" smd rect
			(at 9.199 2.249 90)
			(size 0.5 1.1)
			(layers "F.Cu" "F.Paste" "F.Mask")
			(net 596 "Net-(J11-Pad63)")
			(pintype "passive")
		)
		(pad "64" smd rect
			(at 9.199 -2.249 90)
			(size 0.5 1.1)
			(layers "F.Cu" "F.Paste" "F.Mask")
			(net 597 "Net-(J11-Pad64)")
			(pintype "passive")
		)
		(pad "65" smd rect
			(at 9.999 2.249 90)
			(size 0.5 1.1)
			(layers "F.Cu" "F.Paste" "F.Mask")
			(net 598 "Net-(J11-Pad65)")
			(pintype "passive")
		)
		(pad "66" smd rect
			(at 9.999 -2.249 90)
			(size 0.5 1.1)
			(layers "F.Cu" "F.Paste" "F.Mask")
			(net 599 "Net-(J11-Pad66)")
			(pintype "passive")
		)
		(pad "67" smd rect
			(at 10.8 2.249 90)
			(size 0.5 1.1)
			(layers "F.Cu" "F.Paste" "F.Mask")
			(net 482 "/Peripherals/3V3_CONN")
			(pintype "passive")
		)
		(pad "68" smd rect
			(at 10.8 -2.249 90)
			(size 0.5 1.1)
			(layers "F.Cu" "F.Paste" "F.Mask")
			(net 600 "Net-(J11-Pad68)")
			(pintype "passive")
		)
		(pad "69" smd rect
			(at 11.599 2.249 90)
			(size 0.5 1.1)
			(layers "F.Cu" "F.Paste" "F.Mask")
			(net 482 "/Peripherals/3V3_CONN")
			(pintype "passive")
		)
		(pad "70" smd rect
			(at 11.599 -2.249 90)
			(size 0.5 1.1)
			(layers "F.Cu" "F.Paste" "F.Mask")
			(net 601 "Net-(J11-Pad70)")
			(pintype "passive")
		)
		(pad "71" smd rect
			(at 12.4 2.249 90)
			(size 0.5 1.1)
			(layers "F.Cu" "F.Paste" "F.Mask")
			(net 1 "GND")
			(pintype "passive")
		)
		(pad "72" smd rect
			(at 12.4 -2.249 90)
			(size 0.5 1.1)
			(layers "F.Cu" "F.Paste" "F.Mask")
			(net 1 "GND")
			(pintype "passive")
		)
		(pad "73" smd rect
			(at 13.199 2.249 90)
			(size 0.5 1.1)
			(layers "F.Cu" "F.Paste" "F.Mask")
			(net 483 "/Peripherals/1V8_CONN")
			(pintype "passive")
		)
		(pad "74" smd rect
			(at 13.199 -2.249 90)
			(size 0.5 1.1)
			(layers "F.Cu" "F.Paste" "F.Mask")
			(net 484 "/Peripherals/3V3_STDB_CONN")
			(pintype "passive")
		)
		(pad "75" smd rect
			(at 13.999 2.249 90)
			(size 0.5 1.1)
			(layers "F.Cu" "F.Paste" "F.Mask")
			(net 1 "GND")
			(pintype "passive")
		)
		(pad "76" smd rect
			(at 13.999 -2.249 90)
			(size 0.5 1.1)
			(layers "F.Cu" "F.Paste" "F.Mask")
			(net 1 "GND")
			(pintype "passive")
		)
		(pad "77" smd rect
			(at 14.8 2.249 90)
			(size 0.5 1.1)
			(layers "F.Cu" "F.Paste" "F.Mask")
			(net 479 "/Peripherals/5V_CONN")
			(pintype "passive")
		)
		(pad "78" smd rect
			(at 14.8 -2.249 90)
			(size 0.5 1.1)
			(layers "F.Cu" "F.Paste" "F.Mask")
			(net 485 "/Peripherals/VCC_CONN")
			(pintype "passive")
		)
		(pad "79" smd rect
			(at 15.599 2.249 90)
			(size 0.5 1.1)
			(layers "F.Cu" "F.Paste" "F.Mask")
			(net 479 "/Peripherals/5V_CONN")
			(pintype "passive")
		)
		(pad "80" smd rect
			(at 15.599 -2.249 90)
			(size 0.5 1.1)
			(layers "F.Cu" "F.Paste" "F.Mask")
			(net 485 "/Peripherals/VCC_CONN")
			(pintype "passive")
		)
	)
)
